FILE_TYPE = CONNECTIVITY;
{Allegro Design Entry HDL 17.2-2016 S081 (4005846) 1/11/2022}
"PAGE_NUMBER" = 92;
0"NC";
1"M_H_CPU0_SA_CB<7:0>";
2"M_H_CPU0_SA_CA<6:0>";
3"M_H_CPU0_SB_CA<6:0>";
4"M_H_CPU0_SB_CB<7:0>";
5"M_H_CPU0_SA_DQ<31:0>";
6"M_H_CPU0_SB_DQ<31:0>";
7"M_H_CPU0_SA_DQS_DN<9:0>";
8"M_H_CPU0_SA_DQS_DP<9:0>";
9"M_H_CPU0_SB_DQS_DN<9:0>";
10"M_H_CPU0_SB_DQS_DP<9:0>";
11"GND\g";
12"GND\g";
13"P3V3_STBY\g";
14"I3C_SPD_DDRGL_CPU0_SCL";
15"I3C_SPD_DDRH_CPU0_SCL";
16"I3C_SPD_DDRGL_CPU0_SDA";
17"PWRGD_CHH_CPU0_DIMM";
18"TP_CHH_CPU0_DIMM_RFU_6";
19"TP_CHH_CPU0_DIMM_RFU_5";
20"PD_CHH_CPU0_DIMM_SAA";
21"P3V3_STBY\g";
22"TP_CHH_CPU0_DIMM_RFU_2";
23"TP_CHH_CPU0_DIMM_RFU_1";
24"TP_CHH_CPU0_DIMM_RFU_0";
25"M_H_CPU0_SA_CA<6>";
26"M_H_CPU0_SA_CA<5>";
27"M_H_CPU0_SA_CA<4>";
28"GND\g";
29"P12V_MEM_0\g";
30"GND\g";
31"M_H_CPU0_SB_DQS_DP<9>";
32"M_H_CPU0_SB_DQS_DN<9>";
33"M_H_CPU0_SA_DQS_DP<9>";
34"M_H_CPU0_SA_DQS_DN<9>";
35"M_H_CPU0_SA_DQS_DP<8>";
36"M_H_CPU0_SA_DQS_DN<8>";
37"M_H_CPU0_SB_DQS_DN<7>";
38"M_H_CPU0_SA_DQS_DP<7>";
39"M_H_CPU0_SB_DQS_DP<6>";
40"M_H_CPU0_SB_DQS_DN<6>";
41"M_H_CPU0_SA_DQS_DN<6>";
42"M_H_CPU0_SB_DQS_DP<5>";
43"M_H_CPU0_SB_DQS_DN<5>";
44"M_H_CPU0_SA_DQS_DP<5>";
45"M_H_CPU0_SA_DQS_DN<5>";
46"M_H_CPU0_SB_DQS_DP<4>";
47"M_H_CPU0_SB_DQS_DN<4>";
48"M_H_CPU0_SA_DQS_DP<4>";
49"M_H_CPU0_SA_DQS_DN<4>";
50"M_H_CPU0_SB_DQS_DP<3>";
51"M_H_CPU0_SB_DQS_DN<3>";
52"M_H_CPU0_SA_DQS_DP<3>";
53"M_H_CPU0_SA_DQS_DN<3>";
54"M_H_CPU0_SB_DQS_DP<2>";
55"M_H_CPU0_SB_DQS_DN<2>";
56"M_H_CPU0_SA_DQS_DP<2>";
57"M_H_CPU0_SA_DQS_DN<2>";
58"M_H_CPU0_SB_DQS_DP<1>";
59"M_H_CPU0_SB_DQS_DN<1>";
60"M_H_CPU0_SA_DQS_DP<1>";
61"M_H_CPU0_SA_DQS_DN<1>";
62"M_H_CPU0_SB_DQS_DP<0>";
63"M_H_CPU0_SB_DQS_DN<0>";
64"M_H_CPU0_SA_DQS_DP<0>";
65"M_H_CPU0_SA_DQS_DN<0>";
66"M_H_CPU0_SB_DQS_DP<7>";
67"M_H_CPU0_SB_DQS_DN<8>";
68"M_H_CPU0_SB_DQS_DP<8>";
69"M_H_CPU0_SA_DQS_DP<6>";
70"M_H_CPU0_SA_DQS_DN<7>";
71"M_H_CPU0_SA_DQ<31>";
72"TP_CHH_CPU0_DIMM_RFU_3";
73"TP_CHH_CPU0_DIMM_RFU_4";
74"M_H_CPU0_RESET_N";
75"M_H_CPU0_SB_PAR";
76"M_H_CPU0_SA_PAR";
77"M_H_CPU0_SB_RSP<0>";
78"M_H_CPU0_SA_RSP<0>";
79"M_H_CPU0_SB_DQ<0>";
80"M_H_CPU0_SB_DQ<1>";
81"M_H_CPU0_SB_DQ<2>";
82"M_H_CPU0_SB_DQ<3>";
83"M_H_CPU0_SB_DQ<4>";
84"M_H_CPU0_SB_DQ<5>";
85"M_H_CPU0_SB_DQ<6>";
86"M_H_CPU0_SB_DQ<7>";
87"M_H_CPU0_SB_DQ<8>";
88"M_H_CPU0_SB_DQ<9>";
89"M_H_CPU0_SB_DQ<10>";
90"M_H_CPU0_SB_DQ<11>";
91"M_H_CPU0_SB_DQ<12>";
92"M_H_CPU0_SB_DQ<13>";
93"M_H_CPU0_SB_DQ<14>";
94"M_H_CPU0_SB_DQ<15>";
95"M_H_CPU0_SB_DQ<16>";
96"M_H_CPU0_SB_DQ<17>";
97"M_H_CPU0_SB_DQ<18>";
98"M_H_CPU0_SB_DQ<19>";
99"M_H_CPU0_SB_DQ<20>";
100"M_H_CPU0_SB_DQ<21>";
101"M_H_CPU0_SB_DQ<22>";
102"M_H_CPU0_SB_DQ<23>";
103"M_H_CPU0_SB_DQ<24>";
104"M_H_CPU0_SB_DQ<25>";
105"M_H_CPU0_SB_DQ<26>";
106"M_H_CPU0_SB_DQ<27>";
107"M_H_CPU0_SB_DQ<28>";
108"M_H_CPU0_SB_DQ<29>";
109"M_H_CPU0_SB_DQ<30>";
110"M_H_CPU0_SB_DQ<31>";
111"M_H_CPU0_SA_DQ<0>";
112"M_H_CPU0_SA_DQ<1>";
113"M_H_CPU0_SA_DQ<2>";
114"M_H_CPU0_SA_DQ<3>";
115"M_H_CPU0_SA_DQ<4>";
116"M_H_CPU0_SA_DQ<5>";
117"M_H_CPU0_SA_DQ<6>";
118"M_H_CPU0_SA_DQ<7>";
119"M_H_CPU0_SA_DQ<8>";
120"M_H_CPU0_SA_DQ<9>";
121"M_H_CPU0_SA_DQ<10>";
122"M_H_CPU0_SA_DQ<11>";
123"M_H_CPU0_SA_DQ<12>";
124"M_H_CPU0_SA_DQ<13>";
125"M_H_CPU0_SA_DQ<14>";
126"M_H_CPU0_SA_DQ<15>";
127"M_H_CPU0_SA_DQ<16>";
128"M_H_CPU0_SA_DQ<17>";
129"M_H_CPU0_SA_DQ<18>";
130"M_H_CPU0_SA_DQ<19>";
131"M_H_CPU0_SA_DQ<20>";
132"M_H_CPU0_SA_DQ<21>";
133"M_H_CPU0_SA_DQ<22>";
134"M_H_CPU0_SA_DQ<23>";
135"M_H_CPU0_SA_DQ<24>";
136"M_H_CPU0_SA_DQ<25>";
137"M_H_CPU0_SA_DQ<26>";
138"M_H_CPU0_SA_DQ<27>";
139"M_H_CPU0_SA_DQ<28>";
140"M_H_CPU0_SA_DQ<29>";
141"M_H_CPU0_SA_DQ<30>";
142"M_H_CPU0_SB_CS_N<1>";
143"M_H_CPU0_SA_CS_N<1>";
144"M_H_CPU0_SB_CS_N<0>";
145"M_H_CPU0_SA_CS_N<0>";
146"M_H_CPU0_CLK_DP<0>";
147"M_H_CPU0_CLK_DN<0>";
148"M_H_CPU0_SB_CB<0>";
149"M_H_CPU0_SB_CB<1>";
150"M_H_CPU0_SB_CB<2>";
151"M_H_CPU0_SB_CB<3>";
152"M_H_CPU0_SB_CB<4>";
153"M_H_CPU0_SB_CB<5>";
154"M_H_CPU0_SB_CB<6>";
155"M_H_CPU0_SA_CB<0>";
156"M_H_CPU0_SA_CB<2>";
157"M_H_CPU0_SA_CB<3>";
158"M_H_CPU0_SA_CB<5>";
159"M_H_CPU0_SA_CB<6>";
160"M_H_CPU0_SB_CA<6>";
161"M_H_CPU0_SB_CA<5>";
162"M_H_CPU0_SB_CA<4>";
163"M_H_CPU0_SB_CA<3>";
164"M_H_CPU0_SA_CA<3>";
165"M_H_CPU0_SB_CA<2>";
166"M_H_CPU0_SA_CA<2>";
167"M_H_CPU0_SB_CA<1>";
168"M_H_CPU0_SA_CA<1>";
169"M_H_CPU0_SB_CA<0>";
170"M_H_CPU0_SA_CA<0>";
171"M_H_CPU0_ALERT_N";
172"M_H_CPU0_SB_CB<7>";
173"M_H_CPU0_SA_CB<1>";
174"M_H_CPU0_SA_CB<4>";
175"M_H_CPU0_SA_CB<7>";
176"PWRGD_CHGL_CPU0";
177"PD_CHH_CPU0_DIMM_SAA";
178"GND\g";
%"TAP"
"1","(-6025,4150)","0","mstr_standard","I100";
;
CDS_LIB"mstr_standard"
BODY_TYPE"PLUMBING"
HDL_TAP"TRUE";
"B \NAC \NWC"5;
"S \NAC"
BN"7"118;
%"TAP"
"1","(-6025,4100)","0","mstr_standard","I101";
;
CDS_LIB"mstr_standard"
BODY_TYPE"PLUMBING"
HDL_TAP"TRUE";
"B \NAC \NWC"5;
"S \NAC"
BN"6"117;
%"TAP"
"1","(-6025,4200)","0","mstr_standard","I102";
;
CDS_LIB"mstr_standard"
BODY_TYPE"PLUMBING"
HDL_TAP"TRUE";
"B \NAC \NWC"5;
"S \NAC"
BN"8"119;
%"TAP"
"1","(-6025,4250)","0","mstr_standard","I103";
;
CDS_LIB"mstr_standard"
BODY_TYPE"PLUMBING"
HDL_TAP"TRUE";
"B \NAC \NWC"5;
"S \NAC"
BN"9"120;
%"TAP"
"1","(-6025,4350)","0","mstr_standard","I104";
;
CDS_LIB"mstr_standard"
BODY_TYPE"PLUMBING"
HDL_TAP"TRUE";
"B \NAC \NWC"5;
"S \NAC"
BN"11"122;
%"TAP"
"1","(-6025,4400)","0","mstr_standard","I105";
;
CDS_LIB"mstr_standard"
BODY_TYPE"PLUMBING"
HDL_TAP"TRUE";
"B \NAC \NWC"5;
"S \NAC"
BN"12"123;
%"TAP"
"1","(-6025,4450)","0","mstr_standard","I106";
;
CDS_LIB"mstr_standard"
BODY_TYPE"PLUMBING"
HDL_TAP"TRUE";
"B \NAC \NWC"5;
"S \NAC"
BN"13"124;
%"TAP"
"1","(-6025,4500)","0","mstr_standard","I107";
;
CDS_LIB"mstr_standard"
BODY_TYPE"PLUMBING"
HDL_TAP"TRUE";
"B \NAC \NWC"5;
"S \NAC"
BN"14"125;
%"TAP"
"1","(-6025,4300)","0","mstr_standard","I108";
;
CDS_LIB"mstr_standard"
BODY_TYPE"PLUMBING"
HDL_TAP"TRUE";
"B \NAC \NWC"5;
"S \NAC"
BN"10"121;
%"TAP"
"1","(-6025,4750)","0","mstr_standard","I109";
;
CDS_LIB"mstr_standard"
BODY_TYPE"PLUMBING"
HDL_TAP"TRUE";
"B \NAC \NWC"5;
"S \NAC"
BN"19"130;
%"TAP"
"1","(-6025,4600)","0","mstr_standard","I110";
;
CDS_LIB"mstr_standard"
BODY_TYPE"PLUMBING"
HDL_TAP"TRUE";
"B \NAC \NWC"5;
"S \NAC"
BN"16"127;
%"TAP"
"1","(-6025,4700)","0","mstr_standard","I111";
;
CDS_LIB"mstr_standard"
BODY_TYPE"PLUMBING"
HDL_TAP"TRUE";
"B \NAC \NWC"5;
"S \NAC"
BN"18"129;
%"TAP"
"1","(-6025,4650)","0","mstr_standard","I112";
;
CDS_LIB"mstr_standard"
BODY_TYPE"PLUMBING"
HDL_TAP"TRUE";
"B \NAC \NWC"5;
"S \NAC"
BN"17"128;
%"TAP"
"1","(-6025,4550)","0","mstr_standard","I113";
;
CDS_LIB"mstr_standard"
BODY_TYPE"PLUMBING"
HDL_TAP"TRUE";
"B \NAC \NWC"5;
"S \NAC"
BN"15"126;
%"TAP"
"1","(-6025,4800)","0","mstr_standard","I114";
;
CDS_LIB"mstr_standard"
BODY_TYPE"PLUMBING"
HDL_TAP"TRUE";
"B \NAC \NWC"5;
"S \NAC"
BN"20"131;
%"TAP"
"1","(-6025,4850)","0","mstr_standard","I115";
;
CDS_LIB"mstr_standard"
BODY_TYPE"PLUMBING"
HDL_TAP"TRUE";
"B \NAC \NWC"5;
"S \NAC"
BN"21"132;
%"TAP"
"1","(-6025,4900)","0","mstr_standard","I116";
;
CDS_LIB"mstr_standard"
BODY_TYPE"PLUMBING"
HDL_TAP"TRUE";
"B \NAC \NWC"5;
"S \NAC"
BN"22"133;
%"TAP"
"1","(-6025,5050)","0","mstr_standard","I117";
;
CDS_LIB"mstr_standard"
BODY_TYPE"PLUMBING"
HDL_TAP"TRUE";
"B \NAC \NWC"5;
"S \NAC"
BN"25"136;
%"TAP"
"1","(-6025,4950)","0","mstr_standard","I118";
;
CDS_LIB"mstr_standard"
BODY_TYPE"PLUMBING"
HDL_TAP"TRUE";
"B \NAC \NWC"5;
"S \NAC"
BN"23"134;
%"TAP"
"1","(-6025,5000)","0","mstr_standard","I119";
;
CDS_LIB"mstr_standard"
BODY_TYPE"PLUMBING"
HDL_TAP"TRUE";
"B \NAC \NWC"5;
"S \NAC"
BN"24"135;
%"TAP"
"1","(-6025,5250)","0","mstr_standard","I120";
;
CDS_LIB"mstr_standard"
BODY_TYPE"PLUMBING"
HDL_TAP"TRUE";
"B \NAC \NWC"5;
"S \NAC"
BN"29"140;
%"TAP"
"1","(-6025,5300)","0","mstr_standard","I121";
;
CDS_LIB"mstr_standard"
BODY_TYPE"PLUMBING"
HDL_TAP"TRUE";
"B \NAC \NWC"5;
"S \NAC"
BN"30"141;
%"TAP"
"1","(-6025,5200)","0","mstr_standard","I122";
;
CDS_LIB"mstr_standard"
BODY_TYPE"PLUMBING"
HDL_TAP"TRUE";
"B \NAC \NWC"5;
"S \NAC"
BN"28"139;
%"TAP"
"1","(-6025,5150)","0","mstr_standard","I123";
;
CDS_LIB"mstr_standard"
BODY_TYPE"PLUMBING"
HDL_TAP"TRUE";
"B \NAC \NWC"5;
"S \NAC"
BN"27"138;
%"TAP"
"1","(-6025,5100)","0","mstr_standard","I124";
;
CDS_LIB"mstr_standard"
BODY_TYPE"PLUMBING"
HDL_TAP"TRUE";
"B \NAC \NWC"5;
"S \NAC"
BN"26"137;
%"TAP"
"1","(-6025,5350)","0","mstr_standard","I125";
;
CDS_LIB"mstr_standard"
BODY_TYPE"PLUMBING"
HDL_TAP"TRUE";
"B \NAC \NWC"5;
"S \NAC"
BN"31"71;
%"GND"
"1","(-6425,875)","0","mstr_symbols","I128";
;
SIZE"1B"
CDS_LIB"mstr_symbols"
BOM_COST"MEM"
BODY_TYPE"PLUMBING"
VOLTAGE"0.0"
HDL_POWER"GND";
"A\NAC"11;
%"Q_RES"
"2","(-6425,1175)","0","pure_quanta","I129";
;
LOCATION"R765"
$SEC"1"
CDS_SEC"1"
WATTAGE"1/16W"
MATERIAL"CHIP"
TOLERANCE"1%"
VALUE"15.4K"
PART_NUMBER"CS31542FB02"
PACK_TYPE"0402LF"
CDS_LIB"pure_quanta";
"A"
$PN"1"177;
"B"
$PN"2"11;
%"GND"
"1","(-2200,1875)","0","mstr_symbols","I140";
;
SIZE"1B"
CDS_LIB"mstr_symbols"
BODY_TYPE"PLUMBING"
VOLTAGE"0.0"
HDL_POWER"GND";
"A\NAC"30;
%"GND"
"1","(-400,1650)","0","mstr_symbols","I141";
;
SIZE"1B"
CDS_LIB"mstr_symbols"
BODY_TYPE"PLUMBING"
VOLTAGE"0.0"
HDL_POWER"GND";
"A\NAC"28;
%"SCONN288_DDR506112002KQ"
"3","(-1300,3650)","0","pure_quanta","I177";
;
LOCATION"J69"
$SEC"3"
CDS_SEC"3"
PART_TYPE"SMLF"
MATERIAL"IO"
VALUE"SCONN288_DDR506112002KQ"
PART_NUMBER"DFHST8FS479"
CDS_LMAN_SYM_OUTLINE"-450,1800,450,-1750"
NEEDS_NO_SIZE"TRUE"
CDS_LIB"pure_quanta";
"G3"
$PN"G3"28;
"G2"
$PN"G2"28;
"G1"
$PN"G1"28;
"VSS62"
$PN"141"28;
"VSS61"
$PN"139"28;
"VSS60"
$PN"136"28;
"VSS58"
$PN"132"28;
"VSS104"
$PN"240"30;
"VSS102"
$PN"235"30;
"VSS100"
$PN"230"30;
"VIN_BULK2"
$PN"146"29;
"VIN_BULK1"
$PN"145"29;
"VIN_BULK0"
$PN"1"29;
"VSS126"
$PN"288"30;
"VSS125"
$PN"286"30;
"VSS124"
$PN"284"30;
"VSS123"
$PN"281"30;
"VSS122"
$PN"279"30;
"VSS121"
$PN"277"30;
"VSS120"
$PN"275"30;
"VSS119"
$PN"273"30;
"VSS118"
$PN"270"30;
"VSS117"
$PN"268"30;
"VSS116"
$PN"266"30;
"VSS115"
$PN"264"30;
"VSS114"
$PN"262"30;
"VSS113"
$PN"259"30;
"VSS112"
$PN"257"30;
"VSS111"
$PN"255"30;
"VSS110"
$PN"253"30;
"VSS109"
$PN"251"30;
"VSS108"
$PN"248"30;
"VSS107"
$PN"246"30;
"VSS106"
$PN"244"30;
"VSS105"
$PN"242"30;
"VSS103"
$PN"237"30;
"VSS101"
$PN"233"30;
"VSS99"
$PN"228"30;
"VSS98"
$PN"226"30;
"VSS97"
$PN"224"30;
"VSS96"
$PN"222"30;
"VSS95"
$PN"219"30;
"VSS94"
$PN"216"30;
"VSS93"
$PN"214"30;
"VSS92"
$PN"212"30;
"VSS91"
$PN"210"30;
"VSS90"
$PN"208"30;
"VSS89"
$PN"206"30;
"VSS88"
$PN"204"30;
"VSS87"
$PN"202"30;
"VSS86"
$PN"199"30;
"VSS85"
$PN"197"30;
"VSS84"
$PN"195"30;
"VSS83"
$PN"193"30;
"VSS82"
$PN"191"30;
"VSS81"
$PN"188"30;
"VSS80"
$PN"186"30;
"VSS79"
$PN"184"30;
"VSS78"
$PN"182"30;
"VSS77"
$PN"180"30;
"VSS76"
$PN"177"30;
"VSS75"
$PN"175"30;
"VSS74"
$PN"173"30;
"VSS73"
$PN"171"30;
"VSS72"
$PN"169"30;
"VSS71"
$PN"166"30;
"VSS70"
$PN"164"30;
"VSS69"
$PN"162"30;
"VSS68"
$PN"160"30;
"VSS67"
$PN"158"30;
"VSS66"
$PN"155"30;
"VSS65"
$PN"153"30;
"VSS64"
$PN"151"30;
"VSS63"
$PN"143"28;
"VSS59"
$PN"134"28;
"VSS57"
$PN"130"28;
"VSS56"
$PN"128"28;
"VSS55"
$PN"125"28;
"VSS54"
$PN"123"28;
"VSS53"
$PN"121"28;
"VSS52"
$PN"119"28;
"VSS51"
$PN"117"28;
"VSS50"
$PN"114"28;
"VSS49"
$PN"112"28;
"VSS48"
$PN"110"28;
"VSS47"
$PN"108"28;
"VSS46"
$PN"106"28;
"VSS45"
$PN"103"28;
"VSS44"
$PN"101"28;
"VSS43"
$PN"99"28;
"VSS42"
$PN"97"28;
"VSS41"
$PN"95"28;
"VSS40"
$PN"92"28;
"VSS39"
$PN"90"28;
"VSS38"
$PN"88"28;
"VSS37"
$PN"85"28;
"VSS36"
$PN"83"28;
"VSS35"
$PN"81"28;
"VSS34"
$PN"79"28;
"VSS33"
$PN"77"28;
"VSS32"
$PN"75"28;
"VSS31"
$PN"73"28;
"VSS30"
$PN"71"28;
"VSS29"
$PN"69"28;
"VSS28"
$PN"67"28;
"VSS27"
$PN"65"28;
"VSS26"
$PN"63"28;
"VSS25"
$PN"61"28;
"VSS24"
$PN"59"28;
"VSS23"
$PN"57"28;
"VSS22"
$PN"54"28;
"VSS21"
$PN"52"28;
"VSS20"
$PN"50"28;
"VSS19"
$PN"48"28;
"VSS18"
$PN"46"28;
"VSS17"
$PN"43"28;
"VSS16"
$PN"41"28;
"VSS15"
$PN"39"28;
"VSS14"
$PN"37"28;
"VSS13"
$PN"35"28;
"VSS12"
$PN"32"28;
"VSS11"
$PN"30"28;
"VSS10"
$PN"28"28;
"VSS9"
$PN"26"28;
"VSS8"
$PN"24"28;
"VSS7"
$PN"21"28;
"VSS6"
$PN"19"28;
"VSS5"
$PN"17"28;
"VSS4"
$PN"15"28;
"VSS3"
$PN"13"28;
"VSS2"
$PN"10"28;
"VSS1"
$PN"8"28;
"VSS0"
$PN"6"28;
%"Q_CAP"
"1","(-8650,3175)","2","pure_quanta","I186";
;
LOCATION"C116"
$SEC"1"
CDS_SEC"1"
MATERIAL"X7R"
TOLERANCE"10%"
VALUE"0.1UF"
VOLTAGE"25V"
PART_NUMBER"CH4104K1B00"
PACK_TYPE"0402"
BOM_COST"MEM"
CDS_LIB"pure_quanta"
ROOM"MEM_CH_A_CPU0_DIMM1";
"B"
$PN"2"12;
"A"
$PN"1"21;
%"GND"
"1","(-8650,2950)","0","mstr_symbols","I187";
;
BOM_COST"MEM"
SIZE"1B"
CDS_LIB"mstr_symbols"
BODY_TYPE"PLUMBING"
VOLTAGE"0"
ROOM"MEM_EFGH_DECOUPLING_CAPS"
HDL_POWER"GND";
"A\NAC"12;
%"Q_RES"
"1","(-8525,2100)","2","pure_quanta","I189";
;
LOCATION"R298"
$SEC"1"
CDS_SEC"1"
VALUE"0"
BOM_COST"MEM"
CDS_LIB"pure_quanta"
WATTAGE"1/16W"
MATERIAL"CHIP"
TOLERANCE"5%"
PART_NUMBER"CS00002JB38"
PACK_TYPE"0402LF"
ROOM"RST_CPU0_PLD_TO_DIMM";
"B"
$PN"2"176;
"A"
$PN"1"17;
%"VCC_CORE"
"1","(-8400,2425)","0","mstr_symbols","I190";
;
HDL_POWER"P3V3_STBY"
CDS_LIB"mstr_symbols"
VOLTAGE"3.3"
ROOM"PVCCINFAON_CPU0_CTRL";
"A"13;
%"Q_RES"
"2","(-8400,2250)","0","pure_quanta","I191";
;
LOCATION"R97"
$SEC"1"
CDS_SEC"1"
PACK_TYPE"0402LF"
MATERIAL"EMPTY"
WATTAGE"1/16W"
TOLERANCE"5%"
VALUE"1K"
BOM_COST"MEM"
CDS_LIB"pure_quanta"
PART_NUMBER"TMP_QCS21002JB34"
ROOM"MEM_CH_A_CPU0_DIMM1";
"A"
$PN"1"13;
"B"
$PN"2"17;
%"TAP"
"1","(-3300,4300)","0","mstr_standard","I197";
;
CDS_LIB"mstr_standard"
BODY_TYPE"PLUMBING"
HDL_TAP"TRUE";
"B \NAC \NWC"7;
"S \NAC"
BN"9"34;
%"TAP"
"1","(-3300,4200)","0","mstr_standard","I198";
;
CDS_LIB"mstr_standard"
BODY_TYPE"PLUMBING"
HDL_TAP"TRUE";
"B \NAC \NWC"7;
"S \NAC"
BN"8"36;
%"TAP"
"1","(-3500,4350)","0","mstr_standard","I199";
;
CDS_LIB"mstr_standard"
BODY_TYPE"PLUMBING"
HDL_TAP"TRUE";
"B \NAC \NWC"8;
"S \NAC"
BN"9"33;
%"TAP"
"1","(-3500,4250)","0","mstr_standard","I200";
;
CDS_LIB"mstr_standard"
BODY_TYPE"PLUMBING"
HDL_TAP"TRUE";
"B \NAC \NWC"8;
"S \NAC"
BN"8"35;
%"TAP"
"1","(-3300,4100)","0","mstr_standard","I201";
;
CDS_LIB"mstr_standard"
BODY_TYPE"PLUMBING"
HDL_TAP"TRUE";
"B \NAC \NWC"7;
"S \NAC"
BN"7"70;
%"TAP"
"1","(-3300,4000)","0","mstr_standard","I202";
;
CDS_LIB"mstr_standard"
BODY_TYPE"PLUMBING"
HDL_TAP"TRUE";
"B \NAC \NWC"7;
"S \NAC"
BN"6"41;
%"TAP"
"1","(-3300,3800)","0","mstr_standard","I203";
;
CDS_LIB"mstr_standard"
BODY_TYPE"PLUMBING"
HDL_TAP"TRUE";
"B \NAC \NWC"7;
"S \NAC"
BN"4"49;
%"TAP"
"1","(-3300,3900)","0","mstr_standard","I204";
;
CDS_LIB"mstr_standard"
BODY_TYPE"PLUMBING"
HDL_TAP"TRUE";
"B \NAC \NWC"7;
"S \NAC"
BN"5"45;
%"TAP"
"1","(-3300,3700)","0","mstr_standard","I205";
;
CDS_LIB"mstr_standard"
BODY_TYPE"PLUMBING"
HDL_TAP"TRUE";
"B \NAC \NWC"7;
"S \NAC"
BN"3"53;
%"TAP"
"1","(-3500,3950)","0","mstr_standard","I206";
;
CDS_LIB"mstr_standard"
BODY_TYPE"PLUMBING"
HDL_TAP"TRUE";
"B \NAC \NWC"8;
"S \NAC"
BN"5"44;
%"TAP"
"1","(-3500,4150)","0","mstr_standard","I207";
;
CDS_LIB"mstr_standard"
BODY_TYPE"PLUMBING"
HDL_TAP"TRUE";
"B \NAC \NWC"8;
"S \NAC"
BN"7"38;
%"TAP"
"1","(-3500,4050)","0","mstr_standard","I208";
;
CDS_LIB"mstr_standard"
BODY_TYPE"PLUMBING"
HDL_TAP"TRUE";
"B \NAC \NWC"8;
"S \NAC"
BN"6"69;
%"TAP"
"1","(-3500,3850)","0","mstr_standard","I209";
;
CDS_LIB"mstr_standard"
BODY_TYPE"PLUMBING"
HDL_TAP"TRUE";
"B \NAC \NWC"8;
"S \NAC"
BN"4"48;
%"TAP"
"1","(-3500,3750)","0","mstr_standard","I210";
;
CDS_LIB"mstr_standard"
BODY_TYPE"PLUMBING"
HDL_TAP"TRUE";
"B \NAC \NWC"8;
"S \NAC"
BN"3"52;
%"TAP"
"1","(-3300,3600)","0","mstr_standard","I211";
;
CDS_LIB"mstr_standard"
BODY_TYPE"PLUMBING"
HDL_TAP"TRUE";
"B \NAC \NWC"7;
"S \NAC"
BN"2"57;
%"TAP"
"1","(-3300,3500)","0","mstr_standard","I212";
;
CDS_LIB"mstr_standard"
BODY_TYPE"PLUMBING"
HDL_TAP"TRUE";
"B \NAC \NWC"7;
"S \NAC"
BN"1"61;
%"TAP"
"1","(-3300,3400)","0","mstr_standard","I213";
;
CDS_LIB"mstr_standard"
BODY_TYPE"PLUMBING"
HDL_TAP"TRUE";
"B \NAC \NWC"7;
"S \NAC"
BN"0"65;
%"TAP"
"1","(-3300,3150)","0","mstr_standard","I214";
;
CDS_LIB"mstr_standard"
BODY_TYPE"PLUMBING"
HDL_TAP"TRUE";
"B \NAC \NWC"9;
"S \NAC"
BN"8"67;
%"TAP"
"1","(-3300,3250)","0","mstr_standard","I215";
;
CDS_LIB"mstr_standard"
BODY_TYPE"PLUMBING"
HDL_TAP"TRUE";
"B \NAC \NWC"9;
"S \NAC"
BN"9"32;
%"TAP"
"1","(-3500,3450)","0","mstr_standard","I216";
;
CDS_LIB"mstr_standard"
BODY_TYPE"PLUMBING"
HDL_TAP"TRUE";
"B \NAC \NWC"8;
"S \NAC"
BN"0"64;
%"TAP"
"1","(-3500,3650)","0","mstr_standard","I217";
;
CDS_LIB"mstr_standard"
BODY_TYPE"PLUMBING"
HDL_TAP"TRUE";
"B \NAC \NWC"8;
"S \NAC"
BN"2"56;
%"TAP"
"1","(-3500,3550)","0","mstr_standard","I218";
;
CDS_LIB"mstr_standard"
BODY_TYPE"PLUMBING"
HDL_TAP"TRUE";
"B \NAC \NWC"8;
"S \NAC"
BN"1"60;
%"TAP"
"1","(-3500,3200)","0","mstr_standard","I219";
;
CDS_LIB"mstr_standard"
BODY_TYPE"PLUMBING"
HDL_TAP"TRUE";
"B \NAC \NWC"10;
"S \NAC"
BN"8"68;
%"SCONN288_DDR506112002KQ"
"1","(-6875,3600)","0","pure_quanta","I22";
;
LOCATION"J69"
$SEC"1"
CDS_SEC"1"
PART_TYPE"SMLF"
MATERIAL"IO"
VALUE"SCONN288_DDR506112002KQ"
PART_NUMBER"DFHST8FS479"
CDS_LMAN_SYM_OUTLINE"-450,1900,450,-1850"
NEEDS_NO_SIZE"TRUE"
CDS_LIB"pure_quanta";
"PWR_GOOD||FAIL_N"
$PN"147"17;
"DQ31_A"
$PN"194"71;
"CB7_A"
$PN"205"175;
"CB4_A"
$PN"58"174;
"CB1_A"
$PN"53"173;
"CB7_B"
$PN"236"172;
"ALERT_N \B"
$PN"62"171;
"CA0_A"
$PN"66"170;
"CA0_B"
$PN"76"169;
"CA1_A"
$PN"211"168;
"CA1_B"
$PN"221"167;
"CA2_A"
$PN"68"166;
"CA2_B"
$PN"78"165;
"CA3_A"
$PN"213"164;
"CA3_B"
$PN"223"163;
"CA4_A"
$PN"70"27;
"CA4_B"
$PN"80"162;
"CA5_A"
$PN"215"26;
"CA5_B"
$PN"225"161;
"CA6_A"
$PN"72"25;
"CA6_B"
$PN"82"160;
"CB6_A"
$PN"203"159;
"CB5_A"
$PN"60"158;
"CB3_A"
$PN"198"157;
"CB2_A"
$PN"196"156;
"CB0_A"
$PN"51"155;
"CB6_B"
$PN"234"154;
"CB5_B"
$PN"91"153;
"CB4_B"
$PN"89"152;
"CB3_B"
$PN"243"151;
"CB2_B"
$PN"241"150;
"CB1_B"
$PN"98"149;
"CB0_B"
$PN"96"148;
"CK_C \B"
$PN"218"147;
"CK_T"
$PN"217"146;
"CS0_A_N"
$PN"64"145;
"CS0_B_N"
$PN"84"144;
"CS1_A_N"
$PN"209"143;
"CS1_B_N"
$PN"229"142;
"DQ30_A"
$PN"192"141;
"DQ29_A"
$PN"49"140;
"DQ28_A"
$PN"47"139;
"DQ27_A"
$PN"187"138;
"DQ26_A"
$PN"185"137;
"DQ25_A"
$PN"42"136;
"DQ24_A"
$PN"40"135;
"DQ23_A"
$PN"183"134;
"DQ22_A"
$PN"181"133;
"DQ21_A"
$PN"38"132;
"DQ20_A"
$PN"36"131;
"DQ19_A"
$PN"176"130;
"DQ18_A"
$PN"174"129;
"DQ17_A"
$PN"31"128;
"DQ16_A"
$PN"29"127;
"DQ15_A"
$PN"172"126;
"DQ14_A"
$PN"170"125;
"DQ13_A"
$PN"27"124;
"DQ12_A"
$PN"25"123;
"DQ11_A"
$PN"165"122;
"DQ10_A"
$PN"163"121;
"DQ9_A"
$PN"20"120;
"DQ8_A"
$PN"18"119;
"DQ7_A"
$PN"161"118;
"DQ6_A"
$PN"159"117;
"DQ5_A"
$PN"16"116;
"DQ4_A"
$PN"14"115;
"DQ3_A"
$PN"154"114;
"DQ2_A"
$PN"152"113;
"DQ1_A"
$PN"9"112;
"DQ0_A"
$PN"7"111;
"DQ31_B"
$PN"287"110;
"DQ30_B"
$PN"285"109;
"DQ29_B"
$PN"142"108;
"DQ28_B"
$PN"140"107;
"DQ27_B"
$PN"280"106;
"DQ26_B"
$PN"278"105;
"DQ25_B"
$PN"135"104;
"DQ24_B"
$PN"133"103;
"DQ23_B"
$PN"276"102;
"DQ22_B"
$PN"274"101;
"DQ21_B"
$PN"131"100;
"DQ20_B"
$PN"129"99;
"DQ19_B"
$PN"269"98;
"DQ18_B"
$PN"267"97;
"DQ17_B"
$PN"124"96;
"DQ16_B"
$PN"122"95;
"DQ15_B"
$PN"265"94;
"DQ14_B"
$PN"263"93;
"DQ13_B"
$PN"120"92;
"DQ12_B"
$PN"118"91;
"DQ11_B"
$PN"258"90;
"DQ10_B"
$PN"256"89;
"DQ9_B"
$PN"113"88;
"DQ8_B"
$PN"111"87;
"DQ7_B"
$PN"254"86;
"DQ6_B"
$PN"252"85;
"DQ5_B"
$PN"109"84;
"DQ4_B"
$PN"107"83;
"DQ3_B"
$PN"247"82;
"DQ2_B"
$PN"245"81;
"DQ1_B"
$PN"102"80;
"DQ0_B"
$PN"100"79;
"HAS"
$PN"148"20;
"HSCL"
$PN"4"15;
"HSDA"
$PN"5"16;
"LBD||RSP_A_N"
$PN"86"78;
"LBS||RSP_B_N"
$PN"87"77;
"PAR_A"
$PN"74"76;
"PAR_B"
$PN"227"75;
"RESET_N \B"
$PN"207"74;
"RFU6"
$PN"232"18;
"RFU5"
$PN"231"19;
"RFU4"
$PN"220"73;
"RFU3"
$PN"150"72;
"RFU2"
$PN"149"22;
"RFU1"
$PN"144"23;
"RFU0"
$PN"2"24;
"VIN_MGMT"
$PN"3"21;
%"TAP"
"1","(-3500,3300)","0","mstr_standard","I220";
;
CDS_LIB"mstr_standard"
BODY_TYPE"PLUMBING"
HDL_TAP"TRUE";
"B \NAC \NWC"10;
"S \NAC"
BN"9"31;
%"TAP"
"1","(-3300,3050)","0","mstr_standard","I221";
;
CDS_LIB"mstr_standard"
BODY_TYPE"PLUMBING"
HDL_TAP"TRUE";
"B \NAC \NWC"9;
"S \NAC"
BN"7"37;
%"TAP"
"1","(-3300,2950)","0","mstr_standard","I222";
;
CDS_LIB"mstr_standard"
BODY_TYPE"PLUMBING"
HDL_TAP"TRUE";
"B \NAC \NWC"9;
"S \NAC"
BN"6"40;
%"TAP"
"1","(-3300,2850)","0","mstr_standard","I223";
;
CDS_LIB"mstr_standard"
BODY_TYPE"PLUMBING"
HDL_TAP"TRUE";
"B \NAC \NWC"9;
"S \NAC"
BN"5"43;
%"TAP"
"1","(-3300,2650)","0","mstr_standard","I224";
;
CDS_LIB"mstr_standard"
BODY_TYPE"PLUMBING"
HDL_TAP"TRUE";
"B \NAC \NWC"9;
"S \NAC"
BN"3"51;
%"TAP"
"1","(-3300,2750)","0","mstr_standard","I225";
;
CDS_LIB"mstr_standard"
BODY_TYPE"PLUMBING"
HDL_TAP"TRUE";
"B \NAC \NWC"9;
"S \NAC"
BN"4"47;
%"TAP"
"1","(-3500,2900)","0","mstr_standard","I226";
;
CDS_LIB"mstr_standard"
BODY_TYPE"PLUMBING"
HDL_TAP"TRUE";
"B \NAC \NWC"10;
"S \NAC"
BN"5"42;
%"TAP"
"1","(-3500,3100)","0","mstr_standard","I227";
;
CDS_LIB"mstr_standard"
BODY_TYPE"PLUMBING"
HDL_TAP"TRUE";
"B \NAC \NWC"10;
"S \NAC"
BN"7"66;
%"TAP"
"1","(-3500,3000)","0","mstr_standard","I228";
;
CDS_LIB"mstr_standard"
BODY_TYPE"PLUMBING"
HDL_TAP"TRUE";
"B \NAC \NWC"10;
"S \NAC"
BN"6"39;
%"TAP"
"1","(-3500,2800)","0","mstr_standard","I229";
;
CDS_LIB"mstr_standard"
BODY_TYPE"PLUMBING"
HDL_TAP"TRUE";
"B \NAC \NWC"10;
"S \NAC"
BN"4"46;
%"TAP"
"1","(-7725,3150)","2","mstr_standard","I23";
;
CDS_LIB"mstr_standard"
BODY_TYPE"PLUMBING"
HDL_TAP"TRUE";
"B \NAC \NWC"4;
"S \NAC"
BN"0"148;
%"TAP"
"1","(-3500,2700)","0","mstr_standard","I230";
;
CDS_LIB"mstr_standard"
BODY_TYPE"PLUMBING"
HDL_TAP"TRUE";
"B \NAC \NWC"10;
"S \NAC"
BN"3"50;
%"TAP"
"1","(-3300,2550)","0","mstr_standard","I231";
;
CDS_LIB"mstr_standard"
BODY_TYPE"PLUMBING"
HDL_TAP"TRUE";
"B \NAC \NWC"9;
"S \NAC"
BN"2"55;
%"TAP"
"1","(-3300,2450)","0","mstr_standard","I232";
;
CDS_LIB"mstr_standard"
BODY_TYPE"PLUMBING"
HDL_TAP"TRUE";
"B \NAC \NWC"9;
"S \NAC"
BN"1"59;
%"TAP"
"1","(-3300,2350)","0","mstr_standard","I233";
;
CDS_LIB"mstr_standard"
BODY_TYPE"PLUMBING"
HDL_TAP"TRUE";
"B \NAC \NWC"9;
"S \NAC"
BN"0"63;
%"TAP"
"1","(-3500,2400)","0","mstr_standard","I234";
;
CDS_LIB"mstr_standard"
BODY_TYPE"PLUMBING"
HDL_TAP"TRUE";
"B \NAC \NWC"10;
"S \NAC"
BN"0"62;
%"TAP"
"1","(-3500,2500)","0","mstr_standard","I235";
;
CDS_LIB"mstr_standard"
BODY_TYPE"PLUMBING"
HDL_TAP"TRUE";
"B \NAC \NWC"10;
"S \NAC"
BN"1"58;
%"TAP"
"1","(-3500,2600)","0","mstr_standard","I236";
;
CDS_LIB"mstr_standard"
BODY_TYPE"PLUMBING"
HDL_TAP"TRUE";
"B \NAC \NWC"10;
"S \NAC"
BN"2"54;
%"SCONN288_DDR506112002KQ"
"2","(-4450,3350)","0","pure_quanta","I237";
;
LOCATION"J69"
$SEC"2"
CDS_SEC"2"
VALUE"SCONN288_DDR506112002KQ"
PART_TYPE"SMLF"
PART_NUMBER"DFHST8FS479"
MATERIAL"IO"
CDS_LMAN_SYM_OUTLINE"-600,1150,600,-1150"
NEEDS_NO_SIZE"TRUE"
CDS_LIB"pure_quanta";
"DQS7_A_C||TDQS7_A_C \B"
$PN"178"70;
"DQS6_A_T||TDQS6_A_T"
$PN"168"69;
"DQS8_B_T||TDQS8_B_T"
$PN"283"68;
"DQS8_B_C||TDQS8_B_C \B"
$PN"282"67;
"DQS7_B_T||TDQS7_B_T"
$PN"272"66;
"DQS0_A_C \B"
$PN"12"65;
"DQS0_A_T"
$PN"11"64;
"DQS0_B_C \B"
$PN"105"63;
"DQS0_B_T"
$PN"104"62;
"DQS1_A_C \B"
$PN"23"61;
"DQS1_A_T"
$PN"22"60;
"DQS1_B_C \B"
$PN"116"59;
"DQS1_B_T"
$PN"115"58;
"DQS2_A_C \B"
$PN"34"57;
"DQS2_A_T"
$PN"33"56;
"DQS2_B_C \B"
$PN"127"55;
"DQS2_B_T"
$PN"126"54;
"DQS3_A_C \B"
$PN"45"53;
"DQS3_A_T"
$PN"44"52;
"DQS3_B_C \B"
$PN"138"51;
"DQS3_B_T"
$PN"137"50;
"DQS4_A_C \B"
$PN"56"49;
"DQS4_A_T"
$PN"55"48;
"DQS4_B_C \B"
$PN"238"47;
"DQS4_B_T"
$PN"239"46;
"DQS5_A_C||TDQS5_A_C||DQS5_A_T||TDQS5_A_T \B"
$PN"156"45;
"DQS5_A_T||TDQS5_A_T"
$PN"157"44;
"DQS5_B_C||TDQS5_B_C \B"
$PN"249"43;
"DQS5_B_T||TDQS5_B_T"
$PN"250"42;
"DQS6_A_C||TDQS6_A_C||DQS6_A_T||TDQS6_A_T \B"
$PN"167"41;
"DQS6_B_C||TDQS6_B_C \B"
$PN"260"40;
"DQS6_B_T||TDQS6_B_T"
$PN"261"39;
"DQS7_A_T||TDQS7_A_T"
$PN"179"38;
"DQS7_B_C||TDQS7_B_C \B"
$PN"271"37;
"DQS8_A_C||TDQS8_A_C \B"
$PN"189"36;
"DQS8_A_T||TDQS8_A_T"
$PN"190"35;
"DQS9_A_C||TDQS9_A_C \B"
$PN"200"34;
"DQS9_A_T||TDQS9_A_T"
$PN"201"33;
"DQS9_B_C||TDQS9_B_C \B"
$PN"94"32;
"DQS9_B_T||TDQS9_B_T||DBI4_B_N"
$PN"93"31;
%"GND"
"1","(-2900,5650)","0","pure_quanta_power","I238";
;
CDS_LIB"pure_quanta_power"
BOM_COST"MEM"
SIZE"1B"
ROOM"MEM_EFGH_DECOUPLING_CAPS"
HDL_POWER"GND";
"A<SIZE-1..0>\NAC"178;
%"Q_CAP"
"1","(-2900,6000)","2","pure_quanta","I239";
;
LOCATION"C159"
$SEC"1"
CDS_SEC"1"
MATERIAL"X6S"
TOLERANCE"10%"
VALUE"10UF"
PART_NUMBER"CH6104KEA00"
VOLTAGE"25V"
PACK_TYPE"C0805"
BOM_COST"MEM"
CDS_LIB"pure_quanta"
ROOM"MEM_CH_A_CPU0_DIMM1";
"B"
$PN"2"178;
"A"
$PN"1"29;
%"TAP"
"1","(-7725,3200)","2","mstr_standard","I24";
;
CDS_LIB"mstr_standard"
BODY_TYPE"PLUMBING"
HDL_TAP"TRUE";
"B \NAC \NWC"4;
"S \NAC"
BN"1"149;
%"Q_CAP"
"1","(-2325,6000)","2","pure_quanta","I240";
;
LOCATION"C161"
$SEC"1"
CDS_SEC"1"
VALUE"10UF"
VOLTAGE"25V"
PACK_TYPE"C0805"
TOLERANCE"10%"
MATERIAL"X6S"
PART_NUMBER"CH6104KEA00"
BOM_COST"MEM"
CDS_LIB"pure_quanta"
ROOM"MEM_CH_A_CPU0_DIMM1";
"B"
$PN"2"178;
"A"
$PN"1"29;
%"UNIVERSAL_POWER"
"1","(-2900,6325)","0","pure_quanta_power","I241";
;
HDL_POWER"P12V_MEM_0"
BOM_COST"VR_SYSTEM"
CDS_LIB"pure_quanta_power";
"A"29;
%"Q_RES"
"1","(-7775,2650)","0","pure_quanta","I243";
;
$LOCATION"R1575"
CDS_LOCATION"R1575"
$SEC"1"
CDS_SEC"1"
VALUE"49.9"
CDS_LIB"pure_quanta"
PART_NUMBER"CS04992FB07"
TOLERANCE"1%"
WATTAGE"1/16W"
PACK_TYPE"0402LF"
MATERIAL"CHIP";
"B"
$PN"2"15;
"A"
$PN"1"14;
%"TAP"
"1","(-7725,3250)","2","mstr_standard","I25";
;
CDS_LIB"mstr_standard"
BODY_TYPE"PLUMBING"
HDL_TAP"TRUE";
"B \NAC \NWC"4;
"S \NAC"
BN"2"150;
%"TAP"
"1","(-7725,3300)","2","mstr_standard","I26";
;
CDS_LIB"mstr_standard"
BODY_TYPE"PLUMBING"
HDL_TAP"TRUE";
"B \NAC \NWC"4;
"S \NAC"
BN"3"151;
%"TAP"
"1","(-7725,3350)","2","mstr_standard","I27";
;
CDS_LIB"mstr_standard"
BODY_TYPE"PLUMBING"
HDL_TAP"TRUE";
"B \NAC \NWC"4;
"S \NAC"
BN"4"152;
%"TAP"
"1","(-7725,3450)","2","mstr_standard","I28";
;
CDS_LIB"mstr_standard"
BODY_TYPE"PLUMBING"
HDL_TAP"TRUE";
"B \NAC \NWC"4;
"S \NAC"
BN"6"154;
%"TAP"
"1","(-7725,3400)","2","mstr_standard","I29";
;
CDS_LIB"mstr_standard"
BODY_TYPE"PLUMBING"
HDL_TAP"TRUE";
"B \NAC \NWC"4;
"S \NAC"
BN"5"153;
%"TAP"
"1","(-7725,3500)","2","mstr_standard","I30";
;
CDS_LIB"mstr_standard"
BODY_TYPE"PLUMBING"
HDL_TAP"TRUE";
"B \NAC \NWC"4;
"S \NAC"
BN"7"172;
%"TAP"
"1","(-7725,3600)","2","mstr_standard","I31";
;
CDS_LIB"mstr_standard"
BODY_TYPE"PLUMBING"
HDL_TAP"TRUE";
"B \NAC \NWC"1;
"S \NAC"
BN"0"155;
%"TAP"
"1","(-7725,3650)","2","mstr_standard","I32";
;
CDS_LIB"mstr_standard"
BODY_TYPE"PLUMBING"
HDL_TAP"TRUE";
"B \NAC \NWC"1;
"S \NAC"
BN"1"173;
%"TAP"
"1","(-7725,3700)","2","mstr_standard","I33";
;
CDS_LIB"mstr_standard"
BODY_TYPE"PLUMBING"
HDL_TAP"TRUE";
"B \NAC \NWC"1;
"S \NAC"
BN"2"156;
%"TAP"
"1","(-7725,3750)","2","mstr_standard","I34";
;
CDS_LIB"mstr_standard"
BODY_TYPE"PLUMBING"
HDL_TAP"TRUE";
"B \NAC \NWC"1;
"S \NAC"
BN"3"157;
%"TAP"
"1","(-6025,2150)","0","mstr_standard","I35";
;
CDS_LIB"mstr_standard"
BODY_TYPE"PLUMBING"
HDL_TAP"TRUE";
"B \NAC \NWC"6;
"S \NAC"
BN"0"79;
%"TAP"
"1","(-6025,2200)","0","mstr_standard","I36";
;
CDS_LIB"mstr_standard"
BODY_TYPE"PLUMBING"
HDL_TAP"TRUE";
"B \NAC \NWC"6;
"S \NAC"
BN"1"80;
%"TAP"
"1","(-6025,2250)","0","mstr_standard","I37";
;
CDS_LIB"mstr_standard"
BODY_TYPE"PLUMBING"
HDL_TAP"TRUE";
"B \NAC \NWC"6;
"S \NAC"
BN"2"81;
%"TAP"
"1","(-6025,2300)","0","mstr_standard","I38";
;
CDS_LIB"mstr_standard"
BODY_TYPE"PLUMBING"
HDL_TAP"TRUE";
"B \NAC \NWC"6;
"S \NAC"
BN"3"82;
%"TAP"
"1","(-6025,2350)","0","mstr_standard","I39";
;
CDS_LIB"mstr_standard"
BODY_TYPE"PLUMBING"
HDL_TAP"TRUE";
"B \NAC \NWC"6;
"S \NAC"
BN"4"83;
%"TAP"
"1","(-6025,2400)","0","mstr_standard","I40";
;
CDS_LIB"mstr_standard"
BODY_TYPE"PLUMBING"
HDL_TAP"TRUE";
"B \NAC \NWC"6;
"S \NAC"
BN"5"84;
%"TAP"
"1","(-6025,2450)","0","mstr_standard","I41";
;
CDS_LIB"mstr_standard"
BODY_TYPE"PLUMBING"
HDL_TAP"TRUE";
"B \NAC \NWC"6;
"S \NAC"
BN"6"85;
%"TAP"
"1","(-6025,2500)","0","mstr_standard","I42";
;
CDS_LIB"mstr_standard"
BODY_TYPE"PLUMBING"
HDL_TAP"TRUE";
"B \NAC \NWC"6;
"S \NAC"
BN"7"86;
%"TAP"
"1","(-6025,2550)","0","mstr_standard","I43";
;
CDS_LIB"mstr_standard"
BODY_TYPE"PLUMBING"
HDL_TAP"TRUE";
"B \NAC \NWC"6;
"S \NAC"
BN"8"87;
%"TAP"
"1","(-6025,2600)","0","mstr_standard","I44";
;
CDS_LIB"mstr_standard"
BODY_TYPE"PLUMBING"
HDL_TAP"TRUE";
"B \NAC \NWC"6;
"S \NAC"
BN"9"88;
%"TAP"
"1","(-6025,2650)","0","mstr_standard","I45";
;
CDS_LIB"mstr_standard"
BODY_TYPE"PLUMBING"
HDL_TAP"TRUE";
"B \NAC \NWC"6;
"S \NAC"
BN"10"89;
%"TAP"
"1","(-6025,2700)","0","mstr_standard","I46";
;
CDS_LIB"mstr_standard"
BODY_TYPE"PLUMBING"
HDL_TAP"TRUE";
"B \NAC \NWC"6;
"S \NAC"
BN"11"90;
%"TAP"
"1","(-6025,2750)","0","mstr_standard","I47";
;
CDS_LIB"mstr_standard"
BODY_TYPE"PLUMBING"
HDL_TAP"TRUE";
"B \NAC \NWC"6;
"S \NAC"
BN"12"91;
%"TAP"
"1","(-6025,2800)","0","mstr_standard","I48";
;
CDS_LIB"mstr_standard"
BODY_TYPE"PLUMBING"
HDL_TAP"TRUE";
"B \NAC \NWC"6;
"S \NAC"
BN"13"92;
%"TAP"
"1","(-6025,2850)","0","mstr_standard","I49";
;
CDS_LIB"mstr_standard"
BODY_TYPE"PLUMBING"
HDL_TAP"TRUE";
"B \NAC \NWC"6;
"S \NAC"
BN"14"93;
%"VCC_CORE"
"1","(-8550,3375)","0","mstr_symbols","I5";
;
HDL_POWER"P3V3_STBY"
CDS_LIB"mstr_symbols"
VOLTAGE"3.3"
ROOM"PVCCINFAON_CPU0_CTRL";
"A"21;
%"TAP"
"1","(-6025,2950)","0","mstr_standard","I50";
;
CDS_LIB"mstr_standard"
BODY_TYPE"PLUMBING"
HDL_TAP"TRUE";
"B \NAC \NWC"6;
"S \NAC"
BN"16"95;
%"TAP"
"1","(-6025,2900)","0","mstr_standard","I51";
;
CDS_LIB"mstr_standard"
BODY_TYPE"PLUMBING"
HDL_TAP"TRUE";
"B \NAC \NWC"6;
"S \NAC"
BN"15"94;
%"TAP"
"1","(-6025,3000)","0","mstr_standard","I52";
;
CDS_LIB"mstr_standard"
BODY_TYPE"PLUMBING"
HDL_TAP"TRUE";
"B \NAC \NWC"6;
"S \NAC"
BN"17"96;
%"TAP"
"1","(-6025,3100)","0","mstr_standard","I53";
;
CDS_LIB"mstr_standard"
BODY_TYPE"PLUMBING"
HDL_TAP"TRUE";
"B \NAC \NWC"6;
"S \NAC"
BN"19"98;
%"TAP"
"1","(-6025,3150)","0","mstr_standard","I54";
;
CDS_LIB"mstr_standard"
BODY_TYPE"PLUMBING"
HDL_TAP"TRUE";
"B \NAC \NWC"6;
"S \NAC"
BN"20"99;
%"TAP"
"1","(-6025,3250)","0","mstr_standard","I55";
;
CDS_LIB"mstr_standard"
BODY_TYPE"PLUMBING"
HDL_TAP"TRUE";
"B \NAC \NWC"6;
"S \NAC"
BN"22"101;
%"TAP"
"1","(-6025,3200)","0","mstr_standard","I56";
;
CDS_LIB"mstr_standard"
BODY_TYPE"PLUMBING"
HDL_TAP"TRUE";
"B \NAC \NWC"6;
"S \NAC"
BN"21"100;
%"TAP"
"1","(-6025,3050)","0","mstr_standard","I57";
;
CDS_LIB"mstr_standard"
BODY_TYPE"PLUMBING"
HDL_TAP"TRUE";
"B \NAC \NWC"6;
"S \NAC"
BN"18"97;
%"TAP"
"1","(-6025,3350)","0","mstr_standard","I58";
;
CDS_LIB"mstr_standard"
BODY_TYPE"PLUMBING"
HDL_TAP"TRUE";
"B \NAC \NWC"6;
"S \NAC"
BN"24"103;
%"TAP"
"1","(-6025,3400)","0","mstr_standard","I59";
;
CDS_LIB"mstr_standard"
BODY_TYPE"PLUMBING"
HDL_TAP"TRUE";
"B \NAC \NWC"6;
"S \NAC"
BN"25"104;
%"TAP"
"1","(-6025,3500)","0","mstr_standard","I60";
;
CDS_LIB"mstr_standard"
BODY_TYPE"PLUMBING"
HDL_TAP"TRUE";
"B \NAC \NWC"6;
"S \NAC"
BN"27"106;
%"TAP"
"1","(-6025,3450)","0","mstr_standard","I61";
;
CDS_LIB"mstr_standard"
BODY_TYPE"PLUMBING"
HDL_TAP"TRUE";
"B \NAC \NWC"6;
"S \NAC"
BN"26"105;
%"TAP"
"1","(-6025,3300)","0","mstr_standard","I62";
;
CDS_LIB"mstr_standard"
BODY_TYPE"PLUMBING"
HDL_TAP"TRUE";
"B \NAC \NWC"6;
"S \NAC"
BN"23"102;
%"TAP"
"1","(-6025,3600)","0","mstr_standard","I63";
;
CDS_LIB"mstr_standard"
BODY_TYPE"PLUMBING"
HDL_TAP"TRUE";
"B \NAC \NWC"6;
"S \NAC"
BN"29"108;
%"TAP"
"1","(-6025,3700)","0","mstr_standard","I64";
;
CDS_LIB"mstr_standard"
BODY_TYPE"PLUMBING"
HDL_TAP"TRUE";
"B \NAC \NWC"6;
"S \NAC"
BN"31"110;
%"TAP"
"1","(-6025,3650)","0","mstr_standard","I65";
;
CDS_LIB"mstr_standard"
BODY_TYPE"PLUMBING"
HDL_TAP"TRUE";
"B \NAC \NWC"6;
"S \NAC"
BN"30"109;
%"TAP"
"1","(-6025,3550)","0","mstr_standard","I66";
;
CDS_LIB"mstr_standard"
BODY_TYPE"PLUMBING"
HDL_TAP"TRUE";
"B \NAC \NWC"6;
"S \NAC"
BN"28"107;
%"TAP"
"1","(-7725,3800)","2","mstr_standard","I76";
;
CDS_LIB"mstr_standard"
BODY_TYPE"PLUMBING"
HDL_TAP"TRUE";
"B \NAC \NWC"1;
"S \NAC"
BN"4"174;
%"TAP"
"1","(-7725,3850)","2","mstr_standard","I77";
;
CDS_LIB"mstr_standard"
BODY_TYPE"PLUMBING"
HDL_TAP"TRUE";
"B \NAC \NWC"1;
"S \NAC"
BN"5"158;
%"TAP"
"1","(-7725,3950)","2","mstr_standard","I78";
;
CDS_LIB"mstr_standard"
BODY_TYPE"PLUMBING"
HDL_TAP"TRUE";
"B \NAC \NWC"1;
"S \NAC"
BN"7"175;
%"TAP"
"1","(-7725,3900)","2","mstr_standard","I79";
;
CDS_LIB"mstr_standard"
BODY_TYPE"PLUMBING"
HDL_TAP"TRUE";
"B \NAC \NWC"1;
"S \NAC"
BN"6"159;
%"TAP"
"1","(-7725,4650)","2","mstr_standard","I80";
;
CDS_LIB"mstr_standard"
BODY_TYPE"PLUMBING"
HDL_TAP"TRUE";
"B \NAC \NWC"3;
"S \NAC"
BN"0"169;
%"TAP"
"1","(-7725,4700)","2","mstr_standard","I81";
;
CDS_LIB"mstr_standard"
BODY_TYPE"PLUMBING"
HDL_TAP"TRUE";
"B \NAC \NWC"3;
"S \NAC"
BN"1"167;
%"TAP"
"1","(-7725,4750)","2","mstr_standard","I82";
;
CDS_LIB"mstr_standard"
BODY_TYPE"PLUMBING"
HDL_TAP"TRUE";
"B \NAC \NWC"3;
"S \NAC"
BN"2"165;
%"TAP"
"1","(-7725,4850)","2","mstr_standard","I83";
;
CDS_LIB"mstr_standard"
BODY_TYPE"PLUMBING"
HDL_TAP"TRUE";
"B \NAC \NWC"3;
"S \NAC"
BN"4"162;
%"TAP"
"1","(-7725,4800)","2","mstr_standard","I84";
;
CDS_LIB"mstr_standard"
BODY_TYPE"PLUMBING"
HDL_TAP"TRUE";
"B \NAC \NWC"3;
"S \NAC"
BN"3"163;
%"TAP"
"1","(-7725,4900)","2","mstr_standard","I85";
;
CDS_LIB"mstr_standard"
BODY_TYPE"PLUMBING"
HDL_TAP"TRUE";
"B \NAC \NWC"3;
"S \NAC"
BN"5"161;
%"TAP"
"1","(-7725,4950)","2","mstr_standard","I86";
;
CDS_LIB"mstr_standard"
BODY_TYPE"PLUMBING"
HDL_TAP"TRUE";
"B \NAC \NWC"3;
"S \NAC"
BN"6"160;
%"TAP"
"1","(-7725,5050)","2","mstr_standard","I87";
;
CDS_LIB"mstr_standard"
BODY_TYPE"PLUMBING"
HDL_TAP"TRUE";
"B \NAC \NWC"2;
"S \NAC"
BN"0"170;
%"TAP"
"1","(-7725,5100)","2","mstr_standard","I88";
;
CDS_LIB"mstr_standard"
BODY_TYPE"PLUMBING"
HDL_TAP"TRUE";
"B \NAC \NWC"2;
"S \NAC"
BN"1"168;
%"TAP"
"1","(-7725,5150)","2","mstr_standard","I89";
;
CDS_LIB"mstr_standard"
BODY_TYPE"PLUMBING"
HDL_TAP"TRUE";
"B \NAC \NWC"2;
"S \NAC"
BN"2"166;
%"TAP"
"1","(-7725,5200)","2","mstr_standard","I90";
;
CDS_LIB"mstr_standard"
BODY_TYPE"PLUMBING"
HDL_TAP"TRUE";
"B \NAC \NWC"2;
"S \NAC"
BN"3"164;
%"TAP"
"1","(-7725,5250)","2","mstr_standard","I91";
;
CDS_LIB"mstr_standard"
BODY_TYPE"PLUMBING"
HDL_TAP"TRUE";
"B \NAC \NWC"2;
"S \NAC"
BN"4"27;
%"TAP"
"1","(-7725,5300)","2","mstr_standard","I92";
;
CDS_LIB"mstr_standard"
BODY_TYPE"PLUMBING"
HDL_TAP"TRUE";
"B \NAC \NWC"2;
"S \NAC"
BN"5"26;
%"TAP"
"1","(-7725,5350)","2","mstr_standard","I93";
;
CDS_LIB"mstr_standard"
BODY_TYPE"PLUMBING"
HDL_TAP"TRUE";
"B \NAC \NWC"2;
"S \NAC"
BN"6"25;
%"TAP"
"1","(-6025,3800)","0","mstr_standard","I94";
;
CDS_LIB"mstr_standard"
BODY_TYPE"PLUMBING"
HDL_TAP"TRUE";
"B \NAC \NWC"5;
"S \NAC"
BN"0"111;
%"TAP"
"1","(-6025,3850)","0","mstr_standard","I95";
;
CDS_LIB"mstr_standard"
BODY_TYPE"PLUMBING"
HDL_TAP"TRUE";
"B \NAC \NWC"5;
"S \NAC"
BN"1"112;
%"TAP"
"1","(-6025,3900)","0","mstr_standard","I96";
;
CDS_LIB"mstr_standard"
BODY_TYPE"PLUMBING"
HDL_TAP"TRUE";
"B \NAC \NWC"5;
"S \NAC"
BN"2"113;
%"TAP"
"1","(-6025,3950)","0","mstr_standard","I97";
;
CDS_LIB"mstr_standard"
BODY_TYPE"PLUMBING"
HDL_TAP"TRUE";
"B \NAC \NWC"5;
"S \NAC"
BN"3"114;
%"TAP"
"1","(-6025,4000)","0","mstr_standard","I98";
;
CDS_LIB"mstr_standard"
BODY_TYPE"PLUMBING"
HDL_TAP"TRUE";
"B \NAC \NWC"5;
"S \NAC"
BN"4"115;
%"TAP"
"1","(-6025,4050)","0","mstr_standard","I99";
;
CDS_LIB"mstr_standard"
BODY_TYPE"PLUMBING"
HDL_TAP"TRUE";
"B \NAC \NWC"5;
"S \NAC"
BN"5"116;
END.
